# S9S_MB_2U (Grand Teton) — schematic parts with pin connectivity, parts 3357–3505 of 6093; source: Cadence DE-HDL packaged netlist (pstxprt.dat, pstxnet.dat, pstchip.dat)

R160  Q_RES  0 5% CHIP  pkg 0402LF  page 124 : 1 = PWRGD_DRAMPWRGD_CPU0_AB_R_LVC1 ; 2 = PWRGD_DRAMPWRGD_CPU0_AB_LVC1_R2
R162  Q_RES  0 5% CHIP  pkg 0402LF  page 124 : 1 = PWRGD_DRAMPWRGD_CPU0_CD_R_LVC1 ; 2 = PWRGD_DRAMPWRGD_CPU0_CD_LVC1_R2
R164  Q_RES  0 5% CHIP  pkg 0402LF  page 124 : 1 = PWRGD_DRAMPWRGD_CPU0_EF_R_LVC1 ; 2 = PWRGD_DRAMPWRGD_CPU0_EF_LVC1_R2
R166  Q_RES  0 5% CHIP  pkg 0402LF  page 124 : 1 = PWRGD_DRAMPWRGD_CPU0_GH_R_LVC1 ; 2 = PWRGD_DRAMPWRGD_CPU0_GH_LVC1_R2
R168  Q_RES  0 5% CHIP  pkg 0402LF  page 124 : 1 = PWRGD_CPU0_LVC1_R ; 2 = PWRGD_CPU0_BUF_R
R171  Q_RES  0 5% CHIP  pkg 0402LF  page 124 : 1 = RST_CPU0_LVC1_R_N ; 2 = RST_CPU0_BUF_R_N
R175  Q_RES  100 1% CHIP  pkg 0402LF  page 124 : 1 = PWRGD_DRAMPWRGD_CPU0_AB_LVC1_R2 ; 2 = PVCCD_HV_CPU0
R177  Q_RES  100 1% CHIP  pkg 0402LF  page 124 : 1 = PWRGD_DRAMPWRGD_CPU0_CD_LVC1_R2 ; 2 = PVCCD_HV_CPU0
R179  Q_RES  100 1% CHIP  pkg 0402LF  page 124 : 1 = PWRGD_DRAMPWRGD_CPU0_EF_LVC1_R2 ; 2 = PVCCD_HV_CPU0
R181  Q_RES  100 1% CHIP  pkg 0402LF  page 124 : 1 = PWRGD_DRAMPWRGD_CPU0_GH_LVC1_R2 ; 2 = PVCCD_HV_CPU0
R183  Q_RES  100 1% CHIP  pkg 0402LF  page 124 : 1 = PWRGD_CPU0_BUF_R ; 2 = PVNN_TERM_CPU0
R184  Q_RES  100 1% CHIP  pkg 0402LF  page 124 : 1 = PWRGD_CPU0_BUF_R ; 2 = PWRGD_CPU0_LVC1
R185  Q_RES  100 1% CHIP  pkg 0402LF  page 124 : 1 = RST_CPU0_BUF_R_N ; 2 = PVNN_TERM_CPU0
R186  Q_RES  100 1% CHIP  pkg 0402LF  page 124 : 1 = RST_CPU0_BUF_R_N ; 2 = RST_CPU0_LVC1_N
R188  Q_RES  0 5% CHIP  pkg 0402LF  page 123 : 1 = H_CPU_NMI_LVC1_R_N ; 2 = H_CPU_NMI_LVC1_N
R195  Q_RES  49.9 1% CHIP  pkg 0402LF  page 123 : 1 = H_CPU_NMI_LVC1_N ; 2 = H_CPU0_NMI_LVC1_N
R196  Q_RES  49.9 1% CHIP  pkg 0402LF  page 123 : 1 = H_CPU_NMI_LVC1_N ; 2 = H_CPU1_NMI_LVC1_N
R197  Q_RES  301 1% CHIP  pkg 0402LF  page 123 : 1 = PVNN_TERM_CPU0 ; 2 = H_CPU0_NMI_LVC1_N
R198  Q_RES  301 1% CHIP  pkg 0402LF  page 123 : 1 = PVNN_TERM_CPU1 ; 2 = H_CPU1_NMI_LVC1_N
R200  Q_RES  100 1% CHIP  pkg 0402LF  page 123 : 1 = PVNN_TERM_CPU0 ; 2 = H_CPU0_MEMTRIP_LVC1_R_N
R202  Q_RES  100 1% CHIP  pkg 0402LF  page 123 : 1 = PVNN_TERM_CPU1 ; 2 = H_CPU1_MEMTRIP_LVC1_R_N
R203  Q_RES  1.5K 1% CHIP  pkg 0402LF  page 122 : 1 = H_CPU0_MEMHOT_OUT_LVC1_R_N ; 2 = H_CPU0_MEMHOT_OUT_VT_R_N
R204  Q_RES  1.5K 1% CHIP  pkg 0402LF  page 122 : 1 = H_CPU1_MEMHOT_OUT_LVC1_R_N ; 2 = H_CPU1_MEMHOT_OUT_VT_R_N
R205  Q_RES  1.5K 1% CHIP  pkg 0402LF  page 123 : 1 = H_CPU0_MEMTRIP_LVC1_R_N ; 2 = H_CPU0_MEMTRIP_OUT_VT_R_N
R206  Q_RES  1.5K 1% CHIP  pkg 0402LF  page 123 : 1 = H_CPU1_MEMTRIP_LVC1_R_N ; 2 = H_CPU1_MEMTRIP_OUT_VT_R_N
R208  Q_RES  0 5% CHIP  pkg 0402LF  page 122 : 1 = H_CPU0_MEMHOT_IN_LVC1_R_N ; 2 = H_CPU0_MEMHOT_IN_LVC1_R1_N
R210  Q_RES  0 5% CHIP  pkg 0402LF  page 122 : 1 = H_CPU1_MEMHOT_IN_LVC1_R_N ; 2 = H_CPU1_MEMHOT_IN_LVC1_R1_N
R219  Q_RES  100 1% CHIP  pkg 0402LF  page 122 : 1 = PVNN_TERM_CPU0 ; 2 = H_CPU0_MEMHOT_IN_LVC1_R1_N
R220  Q_RES  100 1% CHIP  pkg 0402LF  page 122 : 1 = PVNN_TERM_CPU1 ; 2 = H_CPU1_MEMHOT_IN_LVC1_R1_N
R223  Q_RES  1K 1% CHIP  pkg 0402LF  page 296 : 1 = P3V3_AUX ; 2 = IRQ_PVCCD_CPU1_VRHOT_LVC3_N
R237  Q_RES  1.5K 1% CHIP  pkg 0402LF  page 121 : 1 = H_CPU0_THERMTRIP_LVC1_R_N ; 2 = H_CPU0_THERMTRIP_VT_R_N
R238  Q_RES  1.5K 1% CHIP  pkg 0402LF  page 121 : 1 = H_CPU1_THERMTRIP_LVC1_R_N ; 2 = H_CPU1_THERMTRIP_VT_R_N
R239  Q_RES  0 5% CHIP  pkg 0402LF  page 121 : 1 = H_CPU0_PROCHOT_LVC1_R_N ; 2 = H_CPU0_PROCHOT_LVC1_N
R240  Q_RES  0 5% CHIP  pkg 0402LF  page 121 : 1 = H_CPU1_PROCHOT_LVC1_R_N ; 2 = H_CPU1_PROCHOT_LVC1_N
R241  Q_RES  4.75K 1% CHIP  pkg 0402LF  page 121 : 1 = P3V3 ; 2 = H_CPU0_THERMTRIP_VT_N
R242  Q_RES  4.75K 1% CHIP  pkg 0402LF  page 121 : 1 = P3V3 ; 2 = H_CPU1_THERMTRIP_VT_N
R243  Q_RES  100 1% CHIP  pkg 0402LF  page 121 : 1 = PVNN_TERM_CPU0 ; 2 = H_CPU0_PROCHOT_LVC1_N
R244  Q_RES  100 1% CHIP  pkg 0402LF  page 121 : 1 = PVNN_TERM_CPU1 ; 2 = H_CPU1_PROCHOT_LVC1_N
R249  Q_RES  240 1% EMPTY  pkg 0402LF  page 120 : 1 = PVNN_TERM_CPU0 ; 2 = FM_S3M_CPU0_LVC1_GPIO_0
R250  Q_RES  240 1% EMPTY  pkg 0402LF  page 120 : 1 = PVNN_TERM_CPU0 ; 2 = FM_S3M_CPU0_LVC1_GPIO_1
R251  Q_RES  240 1% EMPTY  pkg 0402LF  page 120 : 1 = PVNN_TERM_CPU0 ; 2 = FM_S3M_CPU0_LVC1_GPIO_4
R252  Q_RES  240 1% CHIP  pkg 0402LF  page 120 : 1 = PVNN_TERM_CPU0 ; 2 = PUD_PCH_BOOT_MODE_CPU0
R253  Q_RES  240 1% CHIP  pkg 0402LF  page 120 : 1 = PVNN_TERM_CPU0 ; 2 = FM_S3M_CPU0_LVC1_GPIO_2
R254  Q_RES  240 1% CHIP  pkg 0402LF  page 120 : 1 = PVNN_TERM_CPU0 ; 2 = FM_S3M_CPU0_LVC1_GPIO_3
R255  Q_RES  240 1% EMPTY  pkg 0402LF  page 120 : 1 = PVNN_TERM_CPU1 ; 2 = FM_S3M_CPU1_LVC1_GPIO_0
R256  Q_RES  240 1% EMPTY  pkg 0402LF  page 120 : 1 = PVNN_TERM_CPU1 ; 2 = FM_S3M_CPU1_LVC1_GPIO_1
R257  Q_RES  240 1% EMPTY  pkg 0402LF  page 120 : 1 = PVNN_TERM_CPU1 ; 2 = FM_S3M_CPU1_LVC1_GPIO_4
R258  Q_RES  240 1% CHIP  pkg 0402LF  page 120 : 1 = PVNN_TERM_CPU1 ; 2 = PUD_PCH_BOOT_MODE_CPU1
R259  Q_RES  240 1% CHIP  pkg 0402LF  page 120 : 1 = PVNN_TERM_CPU1 ; 2 = FM_S3M_CPU1_LVC1_GPIO_2
R260  Q_RES  240 1% CHIP  pkg 0402LF  page 120 : 1 = PVNN_TERM_CPU1 ; 2 = FM_S3M_CPU1_LVC1_GPIO_3
R261  Q_RES  240 1% EMPTY  pkg 0402LF  page 119 : 1 = PVNN_TERM_CPU1 ; 2 = PU_CPU1_TXT_AGENT
R262  Q_RES  240 1% EMPTY  pkg 0402LF  page 119 : 1 = PVNN_TERM_CPU1 ; 2 = PU_CPU1_SAFE_MODE_BOOT
R263  Q_RES  240 1% EMPTY  pkg 0402LF  page 119 : 1 = PVNN_TERM_CPU1 ; 2 = PU_CPU1_FRMAGENT
R264  Q_RES  240 1% EMPTY  pkg 0402LF  page 119 : 1 = PVNN_TERM_CPU1 ; 2 = H_CPU1_BMCINIT_LVC1
R265  Q_RES  240 1% CHIP  pkg 0402LF  page 119 : 1 = PVNN_TERM_CPU1 ; 2 = PU_CPU1_SOCKET_ID0
R266  Q_RES  240 1% EMPTY  pkg 0402LF  page 119 : 1 = PVNN_TERM_CPU1 ; 2 = PU_CPU1_SOCKET_ID1
R267  Q_RES  240 1% EMPTY  pkg 0402LF  page 119 : 1 = PVNN_TERM_CPU1 ; 2 = PU_CPU1_SOCKET_ID2
R268  Q_RES  240 1% EMPTY  pkg 0402LF  page 119 : 1 = PVNN_TERM_CPU1 ; 2 = PU_CPU1_LEGACY_SKT
R269  Q_RES  33.2 1% CHIP  pkg 0402LF  page 223 : 1 = FM_ADR_MODE1 ; 2 = FM_ADR_MODE1_R
R270  Q_RES  10K 1% CHIP  pkg 0402LF  page 119 : 1 = P3V3_AUX ; 2 = FM_CPU1_PKGID0
R271  Q_RES  10K 1% CHIP  pkg 0402LF  page 119 : 1 = P3V3_AUX ; 2 = FM_CPU1_PKGID1
R272  Q_RES  10K 1% CHIP  pkg 0402LF  page 119 : 1 = P3V3_AUX ; 2 = FM_CPU1_PKGID2
R273  Q_RES  10K 1% CHIP  pkg 0402LF  page 119 : 1 = P3V3_AUX ; 2 = FM_CPU1_PROC_ID0
R274  Q_RES  10K 1% CHIP  pkg 0402LF  page 119 : 1 = P3V3_AUX ; 2 = FM_CPU1_PROC_ID1
R275  Q_RES  240 1% CHIP  pkg 0402LF  page 119 : 1 = PVNN_TERM_CPU0 ; 2 = PU_CPU0_TXT_AGENT
R276  Q_RES  240 1% EMPTY  pkg 0402LF  page 119 : 1 = PVNN_TERM_CPU0 ; 2 = PU_CPU0_SAFE_MODE_BOOT
R277  Q_RES  240 1% CHIP  pkg 0402LF  page 119 : 1 = PVNN_TERM_CPU0 ; 2 = PU_CPU0_FRMAGENT
R278  Q_RES  240 1% EMPTY  pkg 0402LF  page 119 : 1 = PVNN_TERM_CPU0 ; 2 = H_CPU0_BMCINIT_LVC1
R279  Q_RES  240 1% EMPTY  pkg 0402LF  page 119 : 1 = PVNN_TERM_CPU0 ; 2 = PU_CPU0_SOCKET_ID0
R280  Q_RES  240 1% EMPTY  pkg 0402LF  page 119 : 1 = PVNN_TERM_CPU0 ; 2 = PU_CPU0_SOCKET_ID1
R281  Q_RES  240 1% EMPTY  pkg 0402LF  page 119 : 1 = PVNN_TERM_CPU0 ; 2 = PU_CPU0_SOCKET_ID2
R282  Q_RES  240 1% CHIP  pkg 0402LF  page 119 : 1 = PVNN_TERM_CPU0 ; 2 = PU_CPU0_LEGACY_SKT
R283  Q_RES  10K 1% CHIP  pkg 0402LF  page 119 : 1 = P3V3_AUX ; 2 = FM_CPU0_PKGID0
R284  Q_RES  10K 1% CHIP  pkg 0402LF  page 119 : 1 = P3V3_AUX ; 2 = FM_CPU0_PKGID1
R285  Q_RES  10K 1% CHIP  pkg 0402LF  page 119 : 1 = P3V3_AUX ; 2 = FM_CPU0_PKGID2
R286  Q_RES  10K 1% CHIP  pkg 0402LF  page 119 : 1 = P3V3_AUX ; 2 = FM_CPU0_PROC_ID0
R287  Q_RES  10K 1% CHIP  pkg 0402LF  page 119 : 1 = P3V3_AUX ; 2 = FM_CPU0_PROC_ID1
R288  Q_RES  240 1% EMPTY  pkg 0402LF  page 119 : 1 = PVNN_TERM_CPU0 ; 2 = PD_CPU1_TXT_PLTEN
R289  Q_RES  240 1% EMPTY  pkg 0402LF  page 119 : 1 = PD_CPU1_TXT_PLTEN ; 2 = GND
R290  Q_RES  240 1% CHIP  pkg 0402LF  page 119 : 1 = GND ; 2 = PD_CPU1_DMIMODE_OVERRIDE
R291  Q_RES  240 1% EMPTY  pkg 0402LF  page 119 : 1 = GND ; 2 = PD_CPU1_ENH_MCECC_DIS
R292  Q_RES  240 1% EMPTY  pkg 0402LF  page 119 : 1 = PVNN_TERM_CPU0 ; 2 = PD_CPU0_TXT_PLTEN
R293  Q_RES  240 1% EMPTY  pkg 0402LF  page 119 : 1 = PD_CPU0_TXT_PLTEN ; 2 = GND
R294  Q_RES  240 1% EMPTY  pkg 0402LF  page 119 : 1 = GND ; 2 = PD_CPU0_DMIMODE_OVERRIDE
R295  Q_RES  240 1% EMPTY  pkg 0402LF  page 119 : 1 = GND ; 2 = PD_CPU0_ENH_MCECC_DIS
R296  Q_RES  301 1% CHIP  pkg 0402LF  page 118 : 1 = PVNN_TERM_CPU0 ; 2 = H_CPU_CATERR_LVC1_R_N
R297  Q_RES  0 5% CHIP  pkg 0402LF  page 118 : 1 = H_CPU0_CATERR_LVC1_R_N ; 2 = H_CPU_CATERR_LVC1_R_N
R298  Q_RES  301 1% CHIP  pkg 0402LF  page 118 : 1 = PVNN_TERM_CPU1 ; 2 = H_CPU_CATERR_LVC1_R_N
R299  Q_RES  0 5% CHIP  pkg 0402LF  page 118 : 1 = H_CPU1_CATERR_LVC1_R_N ; 2 = H_CPU_CATERR_LVC1_R_N
R301  Q_RES  301 1% CHIP  pkg 0402LF  page 118 : 1 = PVNN_TERM_CPU0 ; 2 = H_CPU_RMCA_LVC1_R_N
R302  Q_RES  0 5% CHIP  pkg 0402LF  page 118 : 1 = H_CPU0_RMCA_LVC1_R_N ; 2 = H_CPU_RMCA_LVC1_R_N
R303  Q_RES  301 1% CHIP  pkg 0402LF  page 118 : 1 = PVNN_TERM_CPU1 ; 2 = H_CPU_RMCA_LVC1_R_N
R304  Q_RES  0 5% CHIP  pkg 0402LF  page 118 : 1 = H_CPU1_RMCA_LVC1_R_N ; 2 = H_CPU_RMCA_LVC1_R_N
R307  Q_RES  1K 1% CHIP  pkg 0402LF  page 284 : 1 = P3V3_AUX ; 2 = PWRGD_PVCCIN_CPU1_R
R308  Q_RES  0 5% CHIP  pkg 0402LF  page 284 : 1 = PWRGD_PVCCIN_CPU1 ; 2 = PWRGD_PVCCIN_CPU1_R
R309  Q_RES  0 5% CHIP  pkg 0402LF  page 284 : 1 = FM_PVCCIN_CPU1_EN ; 2 = PVCCIN_CPU1_EN_R
R310  Q_RES  150 1% CHIP  pkg 0402LF  page 284 : 1 = SVID_CLK0_CPU1_R ; 2 = SVID_CLK_PVCCIN_CPU1_R
R311  Q_RES  0 5% CHIP  pkg 0402LF  page 284 : 1 = SVID_DIO0_CPU1_R ; 2 = SVID_DIO_PVCCIN_CPU1_R
R312  Q_RES  0 5% CHIP  pkg 0402LF  page 284 : 1 = SVID_ALERT0_CPU1_R_N ; 2 = SVID_ALERT_PVCCIN_CPU1_R
R315  Q_RES  33.2 1% CHIP  pkg 0402LF  page 118 : 1 = PWRGD_CPUPWRGD_GTL ; 2 = PWRGD_CPUPWRGD_LVC1_R
R318  Q_RES  10K 1% CHIP  pkg 0402LF  page 229 : 1 = FM_SPD_REMOTE_EN ; 2 = GND
R319  Q_RES  10K 1% CHIP  pkg 0402LF  page 80 : 1 = P3V3_AUX ; 2 = PU_S3M_CPU0_CPLD_STATUS
R320  Q_RES  10K 1% CHIP  pkg 0402LF  page 80 : 1 = P3V3_AUX ; 2 = PU_S3M_CPU0_CPLD_CONFD
R321  Q_RES  10K 1% CHIP  pkg 0402LF  page 80 : 1 = P3V3_AUX ; 2 = FM_S3M_CPU0_CPLD_CONFIG_N
R322  Q_RES  33.2 1% CHIP  pkg 0402LF  page 14 : 1 = H_CPU0_PMSYNC_CPU1_R ; 2 = H_CPU0_PMSYNC_CPU1_R1
R323  Q_RES  0 EMPTY  pkg 1206LF  page 80 : 1 = PVCCINFAON_CPU0 ; 2 = PVNN_TERM_CPU0
R324  Q_RES  0 CHIP  pkg 1206LF  page 80 : 1 = PVNN_MAIN_CPU0 ; 2 = PVNN_TERM_CPU0
R325  Q_RES  10K 1% CHIP  pkg 0402LF  page 80 : 1 = P3V3_AUX ; 2 = PU_S3M_CPU1_CPLD_STATUS
R326  Q_RES  10K 1% CHIP  pkg 0402LF  page 80 : 1 = P3V3_AUX ; 2 = PU_S3M_CPU1_CPLD_CONFD
R327  Q_RES  10K 1% CHIP  pkg 0402LF  page 80 : 1 = P3V3_AUX ; 2 = FM_S3M_CPU1_CPLD_CONFIG_N
R328  Q_RES  100 1% CHIP  pkg 0402LF  page 14 : 1 = SVID_DIO0_CPU0_R ; 2 = PVNN_TERM_CPU0
R329  Q_RES  0 EMPTY  pkg 1206LF  page 80 : 1 = PVCCINFAON_CPU1 ; 2 = PVNN_TERM_CPU1
R330  Q_RES  0 CHIP  pkg 1206LF  page 80 : 1 = PVNN_MAIN_CPU1 ; 2 = PVNN_TERM_CPU1
R331  Q_RES  1K 1% EMPTY  pkg 0402LF  page 127 : 1 = P3V3_AUX ; 2 = PD_PIROM_CPU0_ADDR2
R332  Q_RES  10K 1% CHIP  pkg 0402LF  page 127 : 1 = PD_PIROM_CPU0_ADDR2 ; 2 = GND
R333  Q_RES  1K 1% EMPTY  pkg 0402LF  page 127 : 1 = P3V3_AUX ; 2 = PD_PIROM_CPU0_ADDR1
R334  Q_RES  10K 1% CHIP  pkg 0402LF  page 127 : 1 = PD_PIROM_CPU0_ADDR1 ; 2 = GND
R335  Q_RES  1K 1% EMPTY  pkg 0402LF  page 127 : 1 = P3V3_AUX ; 2 = PD_PIROM_CPU0_ADDR0
R336  Q_RES  0 5% CHIP  pkg 0402LF  page 225 : 1 = H_CPU0_ERR0_LVC1_R_N ; 2 = H_CPU_ERR0_LVC1_R_N
R337  Q_RES  0 5% CHIP  pkg 0402LF  page 225 : 1 = H_CPU1_ERR0_LVC1_R_N ; 2 = H_CPU_ERR0_LVC1_R_N
R338  Q_RES  0 5% CHIP  pkg 0402LF  page 225 : 1 = H_CPU_ERR0_LVC1_R_N ; 2 = H_CPU_ERR0_LVC1_N
R340  Q_RES  0 5% CHIP  pkg 0402LF  page 225 : 1 = H_CPU0_ERR1_LVC1_R_N ; 2 = H_CPU_ERR1_LVC1_R_N
R341  Q_RES  0 5% CHIP  pkg 0402LF  page 225 : 1 = H_CPU1_ERR1_LVC1_R_N ; 2 = H_CPU_ERR1_LVC1_R_N
R342  Q_RES  0 5% CHIP  pkg 0402LF  page 225 : 1 = H_CPU_ERR1_LVC1_R_N ; 2 = H_CPU_ERR1_LVC1_N
R344  Q_RES  0 5% CHIP  pkg 0402LF  page 225 : 1 = H_CPU0_ERR2_LVC1_R_N ; 2 = H_CPU_ERR2_LVC1_R_N
R345  Q_RES  0 5% CHIP  pkg 0402LF  page 225 : 1 = H_CPU1_ERR2_LVC1_R_N ; 2 = H_CPU_ERR2_LVC1_R_N
R346  Q_RES  0 5% CHIP  pkg 0402LF  page 225 : 1 = H_CPU_ERR2_LVC1_R_N ; 2 = H_CPU_ERR2_LVC1_N
R361  Q_RES  1K 1% CHIP  pkg 0402LF  page 278 : 1 = P3V3_AUX ; 2 = PWRGD_PVCCD_HV_CPU0_R
R362  Q_RES  0 5% CHIP  pkg 0402LF  page 278 : 1 = PWRGD_PVCCD_HV_CPU0 ; 2 = PWRGD_PVCCD_HV_CPU0_R
R363  Q_RES  0 5% CHIP  pkg 0402LF  page 278 : 1 = FM_PVCCD_HV_CPU0_EN ; 2 = PVCCD_HV_CPU0_EN_R
R365  Q_RES  0 5% CHIP  pkg 0402LF  page 218 : 1 = FM_CPU_RMCA_CATERR_LVT3_R_N ; 2 = CPU_RMCA_CATERR_LVT3_N
R366  Q_RES  249 1% CHIP  pkg 0402LF  page 218 : 1 = P3V3_AUX ; 2 = LED_CPU_RMCA_CATERR
R367  Q_RES  1K 1% EMPTY  pkg 0402LF  page 198 : 1 = P3V3_AUX ; 2 = FM_PCH_SPKR
R369  Q_RES  1K 1% CHIP  pkg 0402LF  page 198 : 1 = P3V3_AUX ; 2 = FM_ADR_ACK
R371  Q_RES  1K 1% EMPTY  pkg 0402LF  page 198 : 1 = P3V3_AUX ; 2 = FM_PCH_BOOT_BIOS_STRAP
R372  Q_RES  10K 1% CHIP  pkg 0402LF  page 198 : 1 = FM_PCH_BOOT_BIOS_STRAP ; 2 = GND
R374  Q_RES  1K 1% EMPTY  pkg 0402LF  page 198 : 1 = P3V3_AUX ; 2 = FM_SPI_3V3_1V8_VOLTAGE
R375  Q_RES  10K 1% CHIP  pkg 0402LF  page 198 : 1 = FM_SPI_3V3_1V8_VOLTAGE ; 2 = GND
R378  Q_RES  1K 1% EMPTY  pkg 0402LF  page 198 : 1 = P3V3_AUX ; 2 = FM_ADR_MODE1
R379  Q_RES  1K 1% CHIP  pkg 0402LF  page 198 : 1 = FM_ADR_MODE1 ; 2 = GND
R380  Q_RES  1K 1% EMPTY  pkg 0402LF  page 198 : 1 = P3V3_AUX ; 2 = FM_FLASH_SECURITY_STRAP
R381  Q_RES  10K 1% CHIP  pkg 0402LF  page 198 : 1 = FM_FLASH_SECURITY_STRAP ; 2 = GND
R401  Q_RES  10K 1% EMPTY  pkg 0402LF  page 204 : 1 = P3V3_AUX ; 2 = IRQ_TPM_SPI_N
R409  Q_RES  4.7K 1% EMPTY  pkg 0402LF  page 153 : 1 = P3V3_OCP_SFF ; 2 = OCP_SFF_ID0
R410  Q_RES  4.7K 1% CHIP  pkg 0402LF  page 153 : 1 = OCP_SFF_ID0 ; 2 = GND
R413  Q_RES  100K 1% CHIP  pkg 0402LF  page 159 : 1 = GND ; 2 = FM_OCP_V3_2_PWR_GOOD
R414  Q_RES  4.7K 1% EMPTY  pkg 0402LF  page 153 : 1 = P3V3_OCP_SFF ; 2 = OCP_SFF_ID1
R415  Q_RES  4.7K 1% CHIP  pkg 0402LF  page 153 : 1 = OCP_SFF_ID1 ; 2 = GND
R416  Q_RES  0 5% CHIP  pkg 0402LF  page 153 : 1 = OCP_SFF_ISO_BIF0_EN ; 2 = OCP_SFF_BIF0_R_N
